FILE_TYPE = MACRO_DRAWING;
SET COLOR_WIRE YELLOW;
SET COLOR_PROP MONO;
SET COLOR_DOT WHITE;
SET COLOR_ARC YELLOW;
SET COLOR_BODY GREEN;
SET COLOR_NOTE MONO;
SET PROP_DISPLAY VALUE;
SET PAGE_NUMBER P184;
FORCEADD OFFPAGE..3
(-1750 -3425);
FORCEPROP 2 LAST $XR1 119 
J 0
(-1416 -3425);
DISPLAY 0.638298 (-1416 -3425);
PAINT MONO (-1416 -3425);
FORCEPROP 2 LAST $XR0 133 
J 0
(-1536 -3425);
DISPLAY 0.638298 (-1536 -3425);
PAINT MONO (-1536 -3425);
FORCEPROP 2 LAST CDS_LIB mstr_standard
J 0
(-1750 -3425);
PAINT ORANGE (-1750 -3425);
DISPLAY INVISIBLE (-1750 -3425);
FORCEPROP 2 LAST PATH I100
J 0
(-1525 -3375);
DISPLAY 1.021277 (-1525 -3375);
PAINT ORANGE (-1525 -3375);
DISPLAY INVISIBLE (-1525 -3375);
FORCEPROP 1 LAST OFFPAGE TRUE
J 0
(-1425 -3550);
DISPLAY 0.872340 (-1425 -3550);
PAINT GREEN (-1425 -3550);
DISPLAY INVISIBLE (-1425 -3550);
FORCEPROP 1 LAST COMMENT_BODY TRUE
J 0
(-1800 -3525);
DISPLAY 0.872340 (-1800 -3525);
PAINT GREEN (-1800 -3525);
DISPLAY INVISIBLE (-1800 -3525);
FORCEADD GND..1
R 2
(-3225 -3900);
FORCEPROP 3 LASTPIN (-3225 -3850) SIG_NAME GND\g
J 0
(-3215 -3840);
DISPLAY 0.659574 (-3215 -3840);
PAINT MONO (-3215 -3840);
DISPLAY INVISIBLE (-3215 -3840);
FORCEPROP 1 LAST VOLTAGE 0
J 0
(-3225 -3900);
PAINT SKYBLUE (-3225 -3900);
DISPLAY INVISIBLE (-3225 -3900);
FORCEPROP 2 LAST BOM_COST MEM
J 0
(-3225 -3895);
PAINT ORANGE (-3225 -3895);
DISPLAY INVISIBLE (-3225 -3895);
FORCEPROP 1 LAST SIZE 1B
J 2
(-3300 -3950);
DISPLAY 1.170213 (-3300 -3950);
PAINT GREEN (-3300 -3950);
DISPLAY INVISIBLE (-3300 -3950);
FORCEPROP 2 LAST CDS_LIB mstr_symbols
J 0
(-3225 -3900);
PAINT MONO (-3225 -3900);
DISPLAY INVISIBLE (-3225 -3900);
FORCEPROP 1 LAST PATH I101
J 2
(-3300 -3900);
DISPLAY 0.872340 (-3300 -3900);
PAINT AQUA (-3300 -3900);
DISPLAY INVISIBLE (-3300 -3900);
FORCEPROP 2 LAST ROOM DDR4_CH_G
J 0
(-3225 -3895);
PAINT ORANGE (-3225 -3895);
DISPLAY INVISIBLE (-3225 -3895);
FORCEPROP 1 LAST BODY_TYPE PLUMBING
J 2
(-3180 -3943);
DISPLAY 0.340426 (-3180 -3943);
PAINT GREEN (-3180 -3943);
DISPLAY INVISIBLE (-3180 -3943);
FORCEPROP 1 LAST HDL_POWER GND
J 2
(-3225 -3750);
DISPLAY 0.553191 (-3225 -3750);
PAINT GREEN (-3225 -3750);
DISPLAY INVISIBLE (-3225 -3750);
FORCEADD OFFPAGE..6
(-5300 -3675);
FORCEPROP 2 LAST $XR2 191 
J 0
(-5820 -3675);
DISPLAY 0.638298 (-5820 -3675);
PAINT MONO (-5820 -3675);
FORCEPROP 2 LAST $XR1 167 
J 0
(-5700 -3675);
DISPLAY 0.638298 (-5700 -3675);
PAINT MONO (-5700 -3675);
FORCEPROP 2 LAST $XR0 164 
J 0
(-5580 -3675);
DISPLAY 0.638298 (-5580 -3675);
PAINT MONO (-5580 -3675);
FORCEPROP 2 LAST CDS_LIB mstr_standard
J 0
(-5300 -3675);
PAINT MONO (-5300 -3675);
DISPLAY INVISIBLE (-5300 -3675);
FORCEPROP 2 LAST PATH I102
J 0
(-5250 -3600);
DISPLAY 1.021277 (-5250 -3600);
PAINT ORANGE (-5250 -3600);
DISPLAY INVISIBLE (-5250 -3600);
FORCEPROP 1 LAST OFFPAGE TRUE
J 0
(-4975 -3800);
DISPLAY 0.872340 (-4975 -3800);
PAINT GREEN (-4975 -3800);
DISPLAY INVISIBLE (-4975 -3800);
FORCEPROP 1 LAST COMMENT_BODY TRUE
J 0
(-5200 -3750);
DISPLAY 0.872340 (-5200 -3750);
PAINT GREEN (-5200 -3750);
DISPLAY INVISIBLE (-5200 -3750);
FORCEADD OFFPAGE..4
(-1750 -3525);
FORCEPROP 2 LAST $XR2 191 
J 0
(-1324 -3525);
DISPLAY 0.638298 (-1324 -3525);
PAINT MONO (-1324 -3525);
FORCEPROP 2 LAST $XR1 164 
J 0
(-1444 -3525);
DISPLAY 0.638298 (-1444 -3525);
PAINT MONO (-1444 -3525);
FORCEPROP 2 LAST $XR0 167 
J 0
(-1564 -3525);
DISPLAY 0.638298 (-1564 -3525);
PAINT MONO (-1564 -3525);
FORCEPROP 2 LAST CDS_LIB mstr_standard
J 0
(-1750 -3525);
PAINT MONO (-1750 -3525);
DISPLAY INVISIBLE (-1750 -3525);
FORCEPROP 2 LAST PATH I103
J 0
(-1700 -3450);
DISPLAY 1.021277 (-1700 -3450);
PAINT ORANGE (-1700 -3450);
DISPLAY INVISIBLE (-1700 -3450);
FORCEPROP 1 LAST OFFPAGE TRUE
J 0
(-1425 -3650);
DISPLAY 0.872340 (-1425 -3650);
PAINT GREEN (-1425 -3650);
DISPLAY INVISIBLE (-1425 -3650);
FORCEPROP 1 LAST COMMENT_BODY TRUE
J 0
(-1775 -3625);
DISPLAY 0.872340 (-1775 -3625);
PAINT GREEN (-1775 -3625);
DISPLAY INVISIBLE (-1775 -3625);
FORCEADD STANDOFF..2
(-5125 -1900);
FORCEPROP 1 LAST PART_NUMBER H72821-001
J 0
(-5224 -2047);
DISPLAY 0.617021 (-5224 -2047);
PAINT BLUE (-5224 -2047);
FORCEPROP 1 LAST MATERIAL SO
J 0
(-5224 -1701);
DISPLAY 0.617021 (-5224 -1701);
PAINT SKYBLUE (-5224 -1701);
FORCEPROP 2 LASTPIN (-4975 -1900) $PN 1
J 0
(-4965 -1890);
DISPLAY 0.617021 (-4965 -1890);
PAINT ORANGE (-4965 -1890);
FORCEPROP 1 LAST LOCATION RM8D1
J 0
(-5224 -1650);
DISPLAY 0.617021 (-5224 -1650);
PAINT AQUA (-5224 -1650);
FORCEPROP 1 LAST PACK_TYPE TH1
J 0
(-5224 -1599);
PAINT SKYBLUE (-5224 -1599);
DISPLAY INVISIBLE (-5224 -1599);
FORCEPROP 2 LAST CDS_LOCATION RM8D1
J 0
(-5224 -1650);
DISPLAY 0.617021 (-5224 -1650);
PAINT AQUA (-5224 -1650);
DISPLAY INVISIBLE (-5224 -1650);
FORCEPROP 2 LAST SEC 1
J 0
(-5200 -1600);
DISPLAY 0.680851 (-5200 -1600);
PAINT MONO (-5200 -1600);
DISPLAY INVISIBLE (-5200 -1600);
FORCEPROP 2 LAST SEC_TYPE TH1
J 0
(-5200 -1600);
DISPLAY 1.021277 (-5200 -1600);
PAINT ORANGE (-5200 -1600);
DISPLAY INVISIBLE (-5200 -1600);
FORCEPROP 2 LAST CDS_LIB mstr_misc
J 0
(-5125 -1900);
PAINT ORANGE (-5125 -1900);
DISPLAY INVISIBLE (-5125 -1900);
FORCEPROP 1 LAST PATH I104
J 0
(-4950 -1701);
PAINT GREEN (-4950 -1701);
DISPLAY INVISIBLE (-4950 -1701);
FORCEADD GND..1
(-4850 -2125);
FORCEPROP 3 LASTPIN (-4850 -2075) SIG_NAME GND\g
J 0
(-4840 -2065);
DISPLAY 0.659574 (-4840 -2065);
PAINT MONO (-4840 -2065);
DISPLAY INVISIBLE (-4840 -2065);
FORCEPROP 1 LAST VOLTAGE 0.0V
J 0
(-4895 -2168);
DISPLAY 0.340426 (-4895 -2168);
PAINT SKYBLUE (-4895 -2168);
DISPLAY INVISIBLE (-4895 -2168);
FORCEPROP 1 LAST SIZE 1B
J 0
(-4775 -2175);
DISPLAY 0.872340 (-4775 -2175);
PAINT AQUA (-4775 -2175);
DISPLAY INVISIBLE (-4775 -2175);
FORCEPROP 2 LAST CDS_LIB mstr_symbols
J 0
(-4850 -2125);
PAINT ORANGE (-4850 -2125);
DISPLAY INVISIBLE (-4850 -2125);
FORCEPROP 1 LAST PATH I105
J 0
(-4775 -2125);
DISPLAY 0.872340 (-4775 -2125);
PAINT AQUA (-4775 -2125);
DISPLAY INVISIBLE (-4775 -2125);
FORCEPROP 1 LAST BODY_TYPE PLUMBING
J 0
(-4895 -2168);
DISPLAY 0.340426 (-4895 -2168);
PAINT GREEN (-4895 -2168);
DISPLAY INVISIBLE (-4895 -2168);
FORCEPROP 1 LAST HDL_POWER GND
J 0
(-4850 -1975);
DISPLAY 0.872340 (-4850 -1975);
PAINT GREEN (-4850 -1975);
DISPLAY INVISIBLE (-4850 -1975);
FORCEADD SCONN11_H67026001..1
(-3700 -3375);
FORCEPROP 1 LAST LOCATION J8E1
J 0
(-4000 -2825);
DISPLAY 0.617021 (-4000 -2825);
PAINT AQUA (-4000 -2825);
FORCEPROP 1 LAST PART_NUMBER H67026-001
J 0
(-4000 -3875);
DISPLAY 0.617021 (-4000 -3875);
PAINT BLUE (-4000 -3875);
FORCEPROP 2 LASTPIN (-4050 -3175) $PN 1
J 2
(-4060 -3165);
DISPLAY 0.617021 (-4060 -3165);
PAINT ORANGE (-4060 -3165);
FORCEPROP 2 LASTPIN (-4050 -3275) $PN 2
J 2
(-4060 -3265);
DISPLAY 0.617021 (-4060 -3265);
PAINT ORANGE (-4060 -3265);
FORCEPROP 2 LASTPIN (-4050 -3375) $PN 3
J 2
(-4060 -3365);
DISPLAY 0.617021 (-4060 -3365);
PAINT ORANGE (-4060 -3365);
FORCEPROP 2 LASTPIN (-4050 -3475) $PN 4
J 2
(-4060 -3465);
DISPLAY 0.617021 (-4060 -3465);
PAINT ORANGE (-4060 -3465);
FORCEPROP 2 LASTPIN (-4050 -3575) $PN 5
J 2
(-4060 -3565);
DISPLAY 0.617021 (-4060 -3565);
PAINT ORANGE (-4060 -3565);
FORCEPROP 2 LASTPIN (-4050 -3675) $PN 6
J 2
(-4060 -3665);
DISPLAY 0.617021 (-4060 -3665);
PAINT ORANGE (-4060 -3665);
FORCEPROP 2 LASTPIN (-3350 -3225) $PN 7
J 0
(-3340 -3215);
DISPLAY 0.617021 (-3340 -3215);
PAINT ORANGE (-3340 -3215);
FORCEPROP 2 LASTPIN (-3350 -3325) $PN 8
J 0
(-3340 -3315);
DISPLAY 0.617021 (-3340 -3315);
PAINT ORANGE (-3340 -3315);
FORCEPROP 2 LASTPIN (-3350 -3425) $PN 9
J 0
(-3340 -3415);
DISPLAY 0.617021 (-3340 -3415);
PAINT ORANGE (-3340 -3415);
FORCEPROP 2 LASTPIN (-3350 -3525) $PN 10
J 0
(-3340 -3515);
DISPLAY 0.617021 (-3340 -3515);
PAINT ORANGE (-3340 -3515);
FORCEPROP 2 LASTPIN (-3350 -3625) $PN 11
J 0
(-3340 -3615);
DISPLAY 0.617021 (-3340 -3615);
PAINT ORANGE (-3340 -3615);
FORCEPROP 2 LASTPIN (-3350 -3125) $PN MP1
J 0
(-3340 -3115);
DISPLAY 0.617021 (-3340 -3115);
PAINT ORANGE (-3340 -3115);
FORCEPROP 2 LASTPIN (-3350 -3725) $PN MP2
J 0
(-3340 -3715);
DISPLAY 0.617021 (-3340 -3715);
PAINT ORANGE (-3340 -3715);
FORCEPROP 1 LAST MATERIAL CONN
J 0
(-4000 -2875);
DISPLAY 0.617021 (-4000 -2875);
PAINT SKYBLUE (-4000 -2875);
FORCEPROP 1 LAST PACK_TYPE SM
J 0
(-4000 -2775);
PAINT SKYBLUE (-4000 -2775);
DISPLAY INVISIBLE (-4000 -2775);
FORCEPROP 2 LAST CDS_LOCATION J8E1
J 0
(-4000 -2825);
DISPLAY 0.617021 (-4000 -2825);
PAINT AQUA (-4000 -2825);
DISPLAY INVISIBLE (-4000 -2825);
FORCEPROP 2 LAST SEC 1
J 0
(-4000 -2775);
DISPLAY 0.680851 (-4000 -2775);
PAINT MONO (-4000 -2775);
DISPLAY INVISIBLE (-4000 -2775);
FORCEPROP 2 LAST SEC_TYPE SM
J 0
(-4000 -2775);
DISPLAY 1.021277 (-4000 -2775);
PAINT ORANGE (-4000 -2775);
DISPLAY INVISIBLE (-4000 -2775);
FORCEPROP 2 LAST CDS_LIB mstr_sconn
J 0
(-3700 -3375);
PAINT MONO (-3700 -3375);
DISPLAY INVISIBLE (-3700 -3375);
FORCEPROP 1 LAST CDS_LMAN_SYM_OUTLINE -300,450,300,-450
J 0
(-3700 -3375);
DISPLAY 0.468085 (-3700 -3375);
PAINT GREEN (-3700 -3375);
DISPLAY INVISIBLE (-3700 -3375);
FORCEPROP 0 LAST BOM_COST MIO_SECURITY
J 0
(-4000 -2725);
DISPLAY 1.021277 (-4000 -2725);
PAINT ORANGE (-4000 -2725);
DISPLAY INVISIBLE (-4000 -2725);
FORCEPROP 1 LAST PATH I87
J 0
(-3600 -2874);
PAINT GREEN (-3600 -2874);
DISPLAY INVISIBLE (-3600 -2874);
FORCEPROP 0 LAST ROOM TPM
J 0
(-4000 -2725);
DISPLAY 1.021277 (-4000 -2725);
PAINT ORANGE (-4000 -2725);
DISPLAY INVISIBLE (-4000 -2725);
FORCEADD RES..1
(-4750 -3175);
FORCEPROP 1 LAST VALUE 33.2
J 2
(-4800 -3225);
DISPLAY 0.617021 (-4800 -3225);
PAINT SKYBLUE (-4800 -3225);
FORCEPROP 1 LAST PACK_TYPE 0402
J 0
(-4375 -3225);
DISPLAY 0.617021 (-4375 -3225);
PAINT SKYBLUE (-4375 -3225);
FORCEPROP 1 LAST WATTAGE 1/16W
J 2
(-4875 -3225);
DISPLAY 0.617021 (-4875 -3225);
PAINT SKYBLUE (-4875 -3225);
FORCEPROP 1 LAST MATERIAL CHIP
J 0
(-4525 -3225);
DISPLAY 0.617021 (-4525 -3225);
PAINT SKYBLUE (-4525 -3225);
FORCEPROP 1 LASTPIN (-4850 -3175) $PN 1
J 0
(-4838 -3163);
DISPLAY 0.617021 (-4838 -3163);
PAINT ORANGE (-4838 -3163);
FORCEPROP 1 LAST PART_NUMBER G21796-074
J 0
(-4650 -3125);
DISPLAY 0.617021 (-4650 -3125);
PAINT BLUE (-4650 -3125);
FORCEPROP 1 LAST TOLERANCE 1%
J 0
(-4675 -3225);
DISPLAY 0.617021 (-4675 -3225);
PAINT SKYBLUE (-4675 -3225);
FORCEPROP 1 LASTPIN (-4650 -3175) $PN 2
J 0
(-4688 -3163);
DISPLAY 0.617021 (-4688 -3163);
PAINT ORANGE (-4688 -3163);
FORCEPROP 1 LAST LOCATION R8E9
J 0
(-4800 -3125);
DISPLAY 0.617021 (-4800 -3125);
PAINT AQUA (-4800 -3125);
FORCEPROP 2 LAST CDS_LOCATION R8E9
J 0
(-4800 -3125);
DISPLAY 0.617021 (-4800 -3125);
PAINT AQUA (-4800 -3125);
DISPLAY INVISIBLE (-4800 -3125);
FORCEPROP 2 LAST SEC 1
J 0
(-4800 -2975);
DISPLAY 0.680851 (-4800 -2975);
PAINT MONO (-4800 -2975);
DISPLAY INVISIBLE (-4800 -2975);
FORCEPROP 0 LAST BOM_COST MIO_SECURITY
J 0
(-4800 -2875);
DISPLAY 1.021277 (-4800 -2875);
PAINT ORANGE (-4800 -2875);
DISPLAY INVISIBLE (-4800 -2875);
FORCEPROP 2 LAST CDS_LIB mstr_discrete
J 0
(-4750 -3175);
PAINT ORANGE (-4750 -3175);
DISPLAY INVISIBLE (-4750 -3175);
FORCEPROP 2 LAST SEC_TYPE 0402
J 0
(-4800 -2975);
DISPLAY 1.021277 (-4800 -2975);
PAINT ORANGE (-4800 -2975);
DISPLAY INVISIBLE (-4800 -2975);
FORCEPROP 1 LAST PATH I88
J 0
(-4800 -3025);
DISPLAY 0.978723 (-4800 -3025);
PAINT WHITE (-4800 -3025);
DISPLAY INVISIBLE (-4800 -3025);
FORCEPROP 0 LAST ROOM TPM
J 0
(-4800 -2975);
DISPLAY 1.021277 (-4800 -2975);
PAINT ORANGE (-4800 -2975);
DISPLAY INVISIBLE (-4800 -2975);
FORCEADD OFFPAGE..1
(-5300 -3175);
FORCEPROP 2 LAST $XR1 154 
J 0
(-5702 -3175);
DISPLAY 0.638298 (-5702 -3175);
PAINT MONO (-5702 -3175);
FORCEPROP 2 LAST $XR0 121 
J 0
(-5582 -3175);
DISPLAY 0.638298 (-5582 -3175);
PAINT MONO (-5582 -3175);
FORCEPROP 2 LAST CDS_LIB mstr_standard
J 0
(-5300 -3175);
PAINT ORANGE (-5300 -3175);
DISPLAY INVISIBLE (-5300 -3175);
FORCEPROP 2 LAST PATH I89
J 0
(-5550 -3125);
DISPLAY 1.021277 (-5550 -3125);
PAINT ORANGE (-5550 -3125);
DISPLAY INVISIBLE (-5550 -3125);
FORCEPROP 1 LAST OFFPAGE TRUE
J 0
(-4975 -3300);
DISPLAY 0.872340 (-4975 -3300);
PAINT GREEN (-4975 -3300);
DISPLAY INVISIBLE (-4975 -3300);
FORCEPROP 1 LAST COMMENT_BODY TRUE
J 0
(-5175 -3275);
DISPLAY 0.872340 (-5175 -3275);
PAINT GREEN (-5175 -3275);
DISPLAY INVISIBLE (-5175 -3275);
FORCEADD OFFPAGE..1
(-5300 -3275);
FORCEPROP 2 LAST $XR3 145 
J 0
(-5942 -3275);
DISPLAY 0.638298 (-5942 -3275);
PAINT MONO (-5942 -3275);
FORCEPROP 2 LAST $XR2 134 
J 0
(-5822 -3275);
DISPLAY 0.638298 (-5822 -3275);
PAINT MONO (-5822 -3275);
FORCEPROP 2 LAST $XR1 191 
J 0
(-5702 -3275);
DISPLAY 0.638298 (-5702 -3275);
PAINT MONO (-5702 -3275);
FORCEPROP 2 LAST $XR0 146 
J 0
(-5582 -3275);
DISPLAY 0.638298 (-5582 -3275);
PAINT MONO (-5582 -3275);
FORCEPROP 2 LAST CDS_LIB mstr_standard
J 0
(-5300 -3275);
PAINT ORANGE (-5300 -3275);
DISPLAY INVISIBLE (-5300 -3275);
FORCEPROP 2 LAST PATH I90
J 0
(-5550 -3225);
DISPLAY 1.021277 (-5550 -3225);
PAINT ORANGE (-5550 -3225);
DISPLAY INVISIBLE (-5550 -3225);
FORCEPROP 1 LAST OFFPAGE TRUE
J 0
(-4975 -3400);
DISPLAY 0.872340 (-4975 -3400);
PAINT GREEN (-4975 -3400);
DISPLAY INVISIBLE (-4975 -3400);
FORCEPROP 1 LAST COMMENT_BODY TRUE
J 0
(-5175 -3375);
DISPLAY 0.872340 (-5175 -3375);
PAINT GREEN (-5175 -3375);
DISPLAY INVISIBLE (-5175 -3375);
FORCEADD OFFPAGE..1
(-5300 -3575);
FORCEPROP 2 LAST $XR0 121 
J 0
(-5582 -3575);
DISPLAY 0.638298 (-5582 -3575);
PAINT MONO (-5582 -3575);
FORCEPROP 2 LAST CDS_LIB mstr_standard
J 0
(-5300 -3575);
PAINT ORANGE (-5300 -3575);
DISPLAY INVISIBLE (-5300 -3575);
FORCEPROP 2 LAST PATH I91
J 0
(-5550 -3525);
DISPLAY 1.021277 (-5550 -3525);
PAINT ORANGE (-5550 -3525);
DISPLAY INVISIBLE (-5550 -3525);
FORCEPROP 1 LAST OFFPAGE TRUE
J 0
(-4975 -3700);
DISPLAY 0.872340 (-4975 -3700);
PAINT GREEN (-4975 -3700);
DISPLAY INVISIBLE (-4975 -3700);
FORCEPROP 1 LAST COMMENT_BODY TRUE
J 0
(-5175 -3675);
DISPLAY 0.872340 (-5175 -3675);
PAINT GREEN (-5175 -3675);
DISPLAY INVISIBLE (-5175 -3675);
FORCEADD RES..1
(-4750 -3575);
FORCEPROP 1 LAST PACK_TYPE 0402
J 0
(-4375 -3625);
DISPLAY 0.617021 (-4375 -3625);
PAINT SKYBLUE (-4375 -3625);
FORCEPROP 1 LAST MATERIAL CHIP
J 0
(-4525 -3625);
DISPLAY 0.617021 (-4525 -3625);
PAINT SKYBLUE (-4525 -3625);
FORCEPROP 1 LASTPIN (-4650 -3575) $PN 2
J 0
(-4688 -3563);
DISPLAY 0.617021 (-4688 -3563);
PAINT ORANGE (-4688 -3563);
FORCEPROP 1 LAST LOCATION R8D35
J 0
(-5275 -3625);
DISPLAY 0.617021 (-5275 -3625);
PAINT AQUA (-5275 -3625);
FORCEPROP 1 LAST PART_NUMBER G21497-005
J 0
(-5125 -3625);
DISPLAY 0.617021 (-5125 -3625);
PAINT BLUE (-5125 -3625);
FORCEPROP 1 LAST WATTAGE 1/16W
J 2
(-4800 -3625);
DISPLAY 0.617021 (-4800 -3625);
PAINT SKYBLUE (-4800 -3625);
FORCEPROP 1 LAST TOLERANCE 5%
J 0
(-4675 -3625);
DISPLAY 0.617021 (-4675 -3625);
PAINT SKYBLUE (-4675 -3625);
FORCEPROP 1 LAST VALUE 0.0
J 2
(-4725 -3625);
DISPLAY 0.617021 (-4725 -3625);
PAINT SKYBLUE (-4725 -3625);
FORCEPROP 1 LASTPIN (-4850 -3575) $PN 1
J 0
(-4838 -3563);
DISPLAY 0.617021 (-4838 -3563);
PAINT ORANGE (-4838 -3563);
FORCEPROP 2 LAST CDS_LOCATION R8D35
J 0
(-4800 -3525);
DISPLAY 0.617021 (-4800 -3525);
PAINT AQUA (-4800 -3525);
DISPLAY INVISIBLE (-4800 -3525);
FORCEPROP 2 LAST SEC 1
J 0
(-4800 -3375);
DISPLAY 0.680851 (-4800 -3375);
PAINT MONO (-4800 -3375);
DISPLAY INVISIBLE (-4800 -3375);
FORCEPROP 2 LAST SEC_TYPE 0402
J 0
(-4800 -3375);
DISPLAY 1.021277 (-4800 -3375);
PAINT ORANGE (-4800 -3375);
DISPLAY INVISIBLE (-4800 -3375);
FORCEPROP 2 LAST CDS_LIB mstr_discrete
J 0
(-4750 -3575);
PAINT ORANGE (-4750 -3575);
DISPLAY INVISIBLE (-4750 -3575);
FORCEPROP 0 LAST BOM_COST MIO_SECURITY
J 0
(-4800 -3275);
DISPLAY 1.021277 (-4800 -3275);
PAINT ORANGE (-4800 -3275);
DISPLAY INVISIBLE (-4800 -3275);
FORCEPROP 1 LAST PATH I92
J 0
(-4800 -3425);
DISPLAY 0.978723 (-4800 -3425);
PAINT WHITE (-4800 -3425);
DISPLAY INVISIBLE (-4800 -3425);
FORCEPROP 0 LAST ROOM TPM
J 0
(-4800 -3375);
DISPLAY 1.021277 (-4800 -3375);
PAINT ORANGE (-4800 -3375);
DISPLAY INVISIBLE (-4800 -3375);
FORCEADD RES..1
(-4725 -3475);
FORCEPROP 1 LAST PACK_TYPE 0402
J 0
(-4350 -3525);
DISPLAY 0.617021 (-4350 -3525);
PAINT SKYBLUE (-4350 -3525);
FORCEPROP 1 LAST MATERIAL CHIP
J 0
(-4500 -3525);
DISPLAY 0.617021 (-4500 -3525);
PAINT SKYBLUE (-4500 -3525);
FORCEPROP 1 LAST PART_NUMBER G21796-074
J 0
(-5250 -3525);
DISPLAY 0.617021 (-5250 -3525);
PAINT BLUE (-5250 -3525);
FORCEPROP 1 LAST WATTAGE 1/16W
J 2
(-4875 -3525);
DISPLAY 0.617021 (-4875 -3525);
PAINT SKYBLUE (-4875 -3525);
FORCEPROP 1 LASTPIN (-4825 -3475) $PN 1
J 0
(-4813 -3463);
DISPLAY 0.617021 (-4813 -3463);
PAINT ORANGE (-4813 -3463);
FORCEPROP 1 LAST LOCATION R8E13
J 0
(-4900 -3425);
DISPLAY 0.617021 (-4900 -3425);
PAINT AQUA (-4900 -3425);
FORCEPROP 1 LASTPIN (-4625 -3475) $PN 2
J 0
(-4663 -3463);
DISPLAY 0.617021 (-4663 -3463);
PAINT ORANGE (-4663 -3463);
FORCEPROP 1 LAST TOLERANCE 1%
J 0
(-4650 -3525);
DISPLAY 0.617021 (-4650 -3525);
PAINT SKYBLUE (-4650 -3525);
FORCEPROP 1 LAST VALUE 33.2
J 2
(-4800 -3525);
DISPLAY 0.617021 (-4800 -3525);
PAINT SKYBLUE (-4800 -3525);
FORCEPROP 2 LAST CDS_LOCATION R8E13
J 0
(-4775 -3425);
DISPLAY 0.617021 (-4775 -3425);
PAINT AQUA (-4775 -3425);
DISPLAY INVISIBLE (-4775 -3425);
FORCEPROP 2 LAST SEC 1
J 0
(-4775 -3275);
DISPLAY 0.680851 (-4775 -3275);
PAINT MONO (-4775 -3275);
DISPLAY INVISIBLE (-4775 -3275);
FORCEPROP 2 LAST CDS_LIB mstr_discrete
J 0
(-4725 -3475);
PAINT ORANGE (-4725 -3475);
DISPLAY INVISIBLE (-4725 -3475);
FORCEPROP 0 LAST BOM_COST MIO_SECURITY
J 0
(-4775 -3175);
DISPLAY 1.021277 (-4775 -3175);
PAINT ORANGE (-4775 -3175);
DISPLAY INVISIBLE (-4775 -3175);
FORCEPROP 2 LAST SEC_TYPE 0402
J 0
(-4775 -3275);
DISPLAY 1.021277 (-4775 -3275);
PAINT ORANGE (-4775 -3275);
DISPLAY INVISIBLE (-4775 -3275);
FORCEPROP 1 LAST PATH I93
J 0
(-4775 -3325);
DISPLAY 0.978723 (-4775 -3325);
PAINT WHITE (-4775 -3325);
DISPLAY INVISIBLE (-4775 -3325);
FORCEPROP 0 LAST ROOM TPM
J 0
(-4775 -3275);
DISPLAY 1.021277 (-4775 -3275);
PAINT ORANGE (-4775 -3275);
DISPLAY INVISIBLE (-4775 -3275);
FORCEADD OFFPAGE..5
(-5300 -3475);
FORCEPROP 2 LAST $XR1 121 
J 0
(-5675 -3475);
DISPLAY 0.638298 (-5675 -3475);
PAINT MONO (-5675 -3475);
FORCEPROP 2 LAST $XR0 154 
J 0
(-5555 -3475);
DISPLAY 0.638298 (-5555 -3475);
PAINT MONO (-5555 -3475);
FORCEPROP 2 LAST CDS_LIB mstr_standard
J 0
(-5300 -3475);
PAINT ORANGE (-5300 -3475);
DISPLAY INVISIBLE (-5300 -3475);
FORCEPROP 2 LAST PATH I94
J 0
(-5550 -3425);
DISPLAY 1.021277 (-5550 -3425);
PAINT ORANGE (-5550 -3425);
DISPLAY INVISIBLE (-5550 -3425);
FORCEPROP 1 LAST OFFPAGE TRUE
J 0
(-4975 -3600);
DISPLAY 0.872340 (-4975 -3600);
PAINT GREEN (-4975 -3600);
DISPLAY INVISIBLE (-4975 -3600);
FORCEPROP 1 LAST COMMENT_BODY TRUE
J 0
(-5200 -3550);
DISPLAY 0.872340 (-5200 -3550);
PAINT GREEN (-5200 -3550);
DISPLAY INVISIBLE (-5200 -3550);
FORCEADD RES..1
(-4725 -3375);
FORCEPROP 1 LAST PACK_TYPE 0402
J 0
(-4350 -3425);
DISPLAY 0.617021 (-4350 -3425);
PAINT SKYBLUE (-4350 -3425);
FORCEPROP 1 LASTPIN (-4825 -3375) $PN 1
J 0
(-4813 -3363);
DISPLAY 0.617021 (-4813 -3363);
PAINT ORANGE (-4813 -3363);
FORCEPROP 1 LAST PART_NUMBER G21796-074
J 0
(-4625 -3325);
DISPLAY 0.617021 (-4625 -3325);
PAINT BLUE (-4625 -3325);
FORCEPROP 1 LAST VALUE 33.2
J 2
(-4300 -3325);
DISPLAY 0.617021 (-4300 -3325);
PAINT SKYBLUE (-4300 -3325);
FORCEPROP 1 LAST WATTAGE 1/16W
J 2
(-4125 -3325);
DISPLAY 0.617021 (-4125 -3325);
PAINT SKYBLUE (-4125 -3325);
FORCEPROP 1 LAST MATERIAL CHIP
J 0
(-4500 -3425);
DISPLAY 0.617021 (-4500 -3425);
PAINT SKYBLUE (-4500 -3425);
FORCEPROP 1 LASTPIN (-4625 -3375) $PN 2
J 0
(-4663 -3363);
DISPLAY 0.617021 (-4663 -3363);
PAINT ORANGE (-4663 -3363);
FORCEPROP 1 LAST TOLERANCE 1%
J 0
(-4650 -3425);
DISPLAY 0.617021 (-4650 -3425);
PAINT SKYBLUE (-4650 -3425);
FORCEPROP 1 LAST LOCATION R8E10
J 0
(-4775 -3325);
DISPLAY 0.617021 (-4775 -3325);
PAINT AQUA (-4775 -3325);
FORCEPROP 2 LAST CDS_LOCATION R8E10
J 0
(-4775 -3325);
DISPLAY 0.617021 (-4775 -3325);
PAINT AQUA (-4775 -3325);
DISPLAY INVISIBLE (-4775 -3325);
FORCEPROP 2 LAST SEC 1
J 0
(-4775 -3175);
DISPLAY 0.680851 (-4775 -3175);
PAINT MONO (-4775 -3175);
DISPLAY INVISIBLE (-4775 -3175);
FORCEPROP 0 LAST BOM_COST MIO_SECURITY
J 0
(-4775 -3075);
DISPLAY 1.021277 (-4775 -3075);
PAINT ORANGE (-4775 -3075);
DISPLAY INVISIBLE (-4775 -3075);
FORCEPROP 2 LAST CDS_LIB mstr_discrete
J 0
(-4725 -3375);
PAINT ORANGE (-4725 -3375);
DISPLAY INVISIBLE (-4725 -3375);
FORCEPROP 2 LAST SEC_TYPE 0402
J 0
(-4775 -3175);
DISPLAY 1.021277 (-4775 -3175);
PAINT ORANGE (-4775 -3175);
DISPLAY INVISIBLE (-4775 -3175);
FORCEPROP 1 LAST PATH I95
J 0
(-4775 -3225);
DISPLAY 0.978723 (-4775 -3225);
PAINT WHITE (-4775 -3225);
DISPLAY INVISIBLE (-4775 -3225);
FORCEPROP 0 LAST ROOM TPM
J 0
(-4775 -3175);
DISPLAY 1.021277 (-4775 -3175);
PAINT ORANGE (-4775 -3175);
DISPLAY INVISIBLE (-4775 -3175);
FORCEADD OFFPAGE..1
(-5300 -3375);
FORCEPROP 2 LAST $XR3 154 
J 0
(-5942 -3375);
DISPLAY 0.638298 (-5942 -3375);
PAINT MONO (-5942 -3375);
FORCEPROP 2 LAST $XR2 125 
J 0
(-5822 -3375);
DISPLAY 0.638298 (-5822 -3375);
PAINT MONO (-5822 -3375);
FORCEPROP 2 LAST $XR1 121 
J 0
(-5702 -3375);
DISPLAY 0.638298 (-5702 -3375);
PAINT MONO (-5702 -3375);
FORCEPROP 2 LAST $XR0 111 
J 0
(-5582 -3375);
DISPLAY 0.638298 (-5582 -3375);
PAINT MONO (-5582 -3375);
FORCEPROP 2 LAST CDS_LIB mstr_standard
J 0
(-5300 -3375);
PAINT ORANGE (-5300 -3375);
DISPLAY INVISIBLE (-5300 -3375);
FORCEPROP 2 LAST PATH I96
J 0
(-5550 -3325);
DISPLAY 1.021277 (-5550 -3325);
PAINT ORANGE (-5550 -3325);
DISPLAY INVISIBLE (-5550 -3325);
FORCEPROP 1 LAST OFFPAGE TRUE
J 0
(-4975 -3500);
DISPLAY 0.872340 (-4975 -3500);
PAINT GREEN (-4975 -3500);
DISPLAY INVISIBLE (-4975 -3500);
FORCEPROP 1 LAST COMMENT_BODY TRUE
J 0
(-5175 -3475);
DISPLAY 0.872340 (-5175 -3475);
PAINT GREEN (-5175 -3475);
DISPLAY INVISIBLE (-5175 -3475);
FORCEADD P3V3_STBY..1
(-3050 -2900);
FORCEPROP 3 LASTPIN (-3050 -2950) SIG_NAME P3V3_STBY\g
J 0
(-3040 -2940);
DISPLAY 0.659574 (-3040 -2940);
PAINT MONO (-3040 -2940);
DISPLAY INVISIBLE (-3040 -2940);
FORCEPROP 1 LAST VOLTAGE 3.3V
J 0
(-3095 -2943);
DISPLAY 0.340426 (-3095 -2943);
PAINT SKYBLUE (-3095 -2943);
DISPLAY INVISIBLE (-3095 -2943);
FORCEPROP 1 LAST SIZE 1B
J 0
(-3005 -2878);
DISPLAY 0.340426 (-3005 -2878);
PAINT GREEN (-3005 -2878);
DISPLAY INVISIBLE (-3005 -2878);
FORCEPROP 2 LAST CDS_LIB mstr_symbols
J 0
(-3050 -2900);
PAINT MONO (-3050 -2900);
DISPLAY INVISIBLE (-3050 -2900);
FORCEPROP 1 LAST PATH I97
J 0
(-3005 -2898);
DISPLAY 0.340426 (-3005 -2898);
PAINT GREEN (-3005 -2898);
DISPLAY INVISIBLE (-3005 -2898);
FORCEPROP 1 LAST BODY_TYPE PLUMBING
J 0
(-3095 -2943);
DISPLAY 0.340426 (-3095 -2943);
PAINT GREEN (-3095 -2943);
DISPLAY INVISIBLE (-3095 -2943);
FORCEPROP 1 LAST HDL_POWER P3V3_STBY
J 0
(-3350 -3025);
DISPLAY 0.872340 (-3350 -3025);
PAINT ORANGE (-3350 -3025);
DISPLAY INVISIBLE (-3350 -3025);
FORCEADD OFFPAGE..2
(-1750 -3325);
FORCEPROP 2 LAST $XR2 249 
J 0
(-1561 -3361);
DISPLAY 0.638298 (-1561 -3361);
PAINT MONO (-1561 -3361);
FORCEPROP 2 LAST $XR1 157 
J 0
(-1441 -3325);
DISPLAY 0.638298 (-1441 -3325);
PAINT MONO (-1441 -3325);
FORCEPROP 2 LAST $XR0 119 
J 0
(-1561 -3325);
DISPLAY 0.638298 (-1561 -3325);
PAINT MONO (-1561 -3325);
FORCEPROP 2 LAST CDS_LIB mstr_standard
J 0
(-1750 -3325);
PAINT MONO (-1750 -3325);
DISPLAY INVISIBLE (-1750 -3325);
FORCEPROP 2 LAST PATH I98
J 0
(-1700 -3250);
DISPLAY 1.021277 (-1700 -3250);
PAINT ORANGE (-1700 -3250);
DISPLAY INVISIBLE (-1700 -3250);
FORCEPROP 1 LAST OFFPAGE TRUE
J 0
(-1425 -3450);
DISPLAY 0.872340 (-1425 -3450);
PAINT GREEN (-1425 -3450);
DISPLAY INVISIBLE (-1425 -3450);
FORCEPROP 1 LAST COMMENT_BODY TRUE
J 0
(-1795 -3420);
DISPLAY 0.872340 (-1795 -3420);
PAINT GREEN (-1795 -3420);
DISPLAY INVISIBLE (-1795 -3420);
FORCEADD RES..1
(-2575 -3425);
FORCEPROP 1 LAST LOCATION R8E1
J 0
(-2625 -3375);
DISPLAY 0.617021 (-2625 -3375);
PAINT AQUA (-2625 -3375);
FORCEPROP 1 LASTPIN (-2475 -3425) $PN 2
J 0
(-2513 -3413);
DISPLAY 0.617021 (-2513 -3413);
PAINT ORANGE (-2513 -3413);
FORCEPROP 1 LAST TOLERANCE 5%
J 0
(-2500 -3475);
DISPLAY 0.617021 (-2500 -3475);
PAINT SKYBLUE (-2500 -3475);
FORCEPROP 1 LAST WATTAGE 1/16W
J 2
(-2700 -3475);
DISPLAY 0.617021 (-2700 -3475);
PAINT SKYBLUE (-2700 -3475);
FORCEPROP 1 LASTPIN (-2675 -3425) $PN 1
J 0
(-2663 -3413);
DISPLAY 0.617021 (-2663 -3413);
PAINT ORANGE (-2663 -3413);
FORCEPROP 1 LAST PACK_TYPE 0402
J 0
(-2200 -3475);
DISPLAY 0.617021 (-2200 -3475);
PAINT SKYBLUE (-2200 -3475);
FORCEPROP 1 LAST VALUE 0.0
J 2
(-2625 -3475);
DISPLAY 0.617021 (-2625 -3475);
PAINT SKYBLUE (-2625 -3475);
FORCEPROP 1 LAST PART_NUMBER G21497-005
J 0
(-3100 -3475);
DISPLAY 0.617021 (-3100 -3475);
PAINT BLUE (-3100 -3475);
FORCEPROP 1 LAST MATERIAL CHIP
J 0
(-2350 -3475);
DISPLAY 0.617021 (-2350 -3475);
PAINT SKYBLUE (-2350 -3475);
FORCEPROP 2 LAST CDS_LOCATION R8E1
J 0
(-2625 -3375);
DISPLAY 0.617021 (-2625 -3375);
PAINT AQUA (-2625 -3375);
DISPLAY INVISIBLE (-2625 -3375);
FORCEPROP 2 LAST $SEC 1
J 0
(-2625 -3225);
DISPLAY 0.680851 (-2625 -3225);
PAINT MONO (-2625 -3225);
DISPLAY INVISIBLE (-2625 -3225);
FORCEPROP 2 LAST CDS_SEC 1
J 0
(-2625 -3225);
DISPLAY 1.021277 (-2625 -3225);
PAINT ORANGE (-2625 -3225);
DISPLAY INVISIBLE (-2625 -3225);
FORCEPROP 0 LAST BOM_COST MIO_SECURITY
J 0
(-2625 -3125);
DISPLAY 1.021277 (-2625 -3125);
PAINT ORANGE (-2625 -3125);
DISPLAY INVISIBLE (-2625 -3125);
FORCEPROP 2 LAST CDS_LIB mstr_discrete
J 0
(-2575 -3425);
PAINT ORANGE (-2575 -3425);
DISPLAY INVISIBLE (-2575 -3425);
FORCEPROP 1 LAST PATH I99
J 0
(-2625 -3275);
DISPLAY 0.978723 (-2625 -3275);
PAINT WHITE (-2625 -3275);
DISPLAY INVISIBLE (-2625 -3275);
FORCEPROP 0 LAST ROOM TPM
J 0
(-2625 -3225);
DISPLAY 1.021277 (-2625 -3225);
PAINT ORANGE (-2625 -3225);
DISPLAY INVISIBLE (-2625 -3225);
FORCEADD CAD_NOTE..1
(-5425 -4025);
FORCEPROP 0 LAST L1 PLACE R8E9 WITHIN 200 MILS OF SPI_PCH_CLK T-POINT AND WITH 500 MILS OF TPM CONN
J 0
(-5575 -4150);
DISPLAY 1.021277 (-5575 -4150);
PAINT ORANGE (-5575 -4150);
FORCEPROP 0 LAST L3 PLACE R8E10 NEAR TPM CONN
J 0
(-5575 -4300);
DISPLAY 1.021277 (-5575 -4300);
PAINT ORANGE (-5575 -4300);
FORCEPROP 0 LAST L2 PLACE R8E13 NEAR TPM CONN
J 0
(-5575 -4225);
DISPLAY 1.021277 (-5575 -4225);
PAINT ORANGE (-5575 -4225);
FORCEPROP 2 LAST CDS_LIB mstr_symbols
J 0
(-5425 -4025);
PAINT ORANGE (-5425 -4025);
DISPLAY INVISIBLE (-5425 -4025);
FORCEPROP 1 LAST COMMENT_BODY TRUE
J 0
(-5400 -3925);
DISPLAY 0.978723 (-5400 -3925);
PAINT ORANGE (-5400 -3925);
DISPLAY INVISIBLE (-5400 -3925);
FORCEADD INTEL_CORP_BPAGE..1
(350 -5900);
FORCEPROP 1 LAST CDS_CON_LAST_MODIFIED Fri Jun 16 17:49:08 2017
J 0
(-1075 -5575);
DISPLAY 1.361702 (-1075 -5575);
PAINT GREEN (-1075 -5575);
DISPLAY INVISIBLE (-1075 -5575);
FORCEPROP 1 LAST CUSTOM_TXT_CDS <CURRENT_DESIGN_SHEET> OF <TOTAL_DESIGN_SHEETS>
J 0
(-150 -5875);
PAINT ORANGE (-150 -5875);
FORCEPROP 2 LAST CUSTOM_TXT_CDS <XR_PAGE_TITLE>
J 0
(-7540 -650);
DISPLAY 0.638298 (-7540 -650);
PAINT PINK (-7540 -650);
DISPLAY INVISIBLE (-7540 -650);
FORCEPROP 2 LAST CUSTOM_TXT_CDS <CON_LAST_MODIFIED>
J 0
(-3650 -5825);
DISPLAY 1.361702 (-3650 -5825);
PAINT ORANGE (-3650 -5825);
FORCEPROP 1 LAST SCH_TITLE SPI TPM CONNECTOR
J 0
(-7600 -5850);
DISPLAY 1.212766 (-7600 -5850);
PAINT ORANGE (-7600 -5850);
FORCEPROP 2 LAST CDS_LIB mstr_symbols
J 0
(350 -5900);
DISPLAY 1.361702 (350 -5900);
PAINT ORANGE (350 -5900);
DISPLAY INVISIBLE (350 -5900);
FORCEPROP 2 LAST PAGE_BORDER TRUE
J 0
(-7540 -650);
DISPLAY 0.872340 (-7540 -650);
PAINT PINK (-7540 -650);
DISPLAY INVISIBLE (-7540 -650);
FORCEPROP 1 LAST COMMENT_BODY TRUE
J 0
(362 -5888);
DISPLAY 0.617021 (362 -5888);
PAINT GREEN (362 -5888);
DISPLAY INVISIBLE (362 -5888);
FORCEPROP 2 LAST CDS_XR_PAGE_TITLE CR-184 : @BASEBOARD_FAB2_LIB.BASEBOARD_FAB2(SCH_1):PAGE184
J 0
(-7540 -650);
DISPLAY 0.638298 (-7540 -650);
PAINT PINK (-7540 -650);
DISPLAY INVISIBLE (-7540 -650);
WIRE 16 -1 (-3225 -3850)(-3225 -3725);
WIRE 16 -1 (-3225 -3725)(-3225 -3625);
WIRE 16 -1 (-3225 -3725)(-3350 -3725);
WIRE 16 -1 (-3225 -3625)(-3225 -3125);
WIRE 16 -1 (-3225 -3625)(-3350 -3625);
WIRE 16 -1 (-3225 -3125)(-3350 -3125);
WIRE 16 -1 (-4850 -2075)(-4850 -1900);
WIRE 16 -1 (-4850 -1900)(-4975 -1900);
WIRE 16 -1 (-3050 -2950)(-3050 -3225);
WIRE 16 -1 (-3050 -3225)(-3350 -3225);
WIRE 16 -1 (-1800 -3525)(-3350 -3525);
FORCEPROP 0 LAST SIG_NAME SMB_SENSOR_STBY_LVC3_SCL
J 0
(-3130 -3515);
DISPLAY 0.617021 (-3130 -3515);
PAINT ORANGE (-3130 -3515);
WIRE 16 -1 (-2475 -3425)(-1800 -3425);
FORCEPROP 2 LAST SIG_NAME IRQ_PIRQA_SPI_TPM_N
J 0
(-2435 -3415);
DISPLAY 0.617021 (-2435 -3415);
PAINT ORANGE (-2435 -3415);
WIRE 3 2175 (-3600 -3275)(-1250 -3275);
WIRE 3 2175 (-1250 -3275)(-1250 -3375);
WIRE 3 2175 (-3600 -3275)(-3600 -3375);
WIRE 3 2175 (-3600 -3375)(-1250 -3375);
WIRE 16 -1 (-3350 -3325)(-1800 -3325);
FORCEPROP 0 LAST SIG_NAME FM_TPM_PRES_RST_N
J 0
(-2910 -3315);
DISPLAY 0.680851 (-2910 -3315);
PAINT ORANGE (-2910 -3315);
WIRE 16 -1 (-5250 -3675)(-4050 -3675);
FORCEPROP 0 LAST SIG_NAME SMB_SENSOR_STBY_LVC3_SDA
J 0
(-5250 -3664);
DISPLAY 0.617021 (-5250 -3664);
PAINT ORANGE (-5250 -3664);
WIRE 16 -1 (-5250 -3275)(-4050 -3275);
FORCEPROP 2 LAST SIG_NAME RST_PLTRST_BUF_N
J 0
(-5250 -3265);
DISPLAY 0.617021 (-5250 -3265);
PAINT ORANGE (-5250 -3265);
WIRE 16 -1 (-4650 -3575)(-4050 -3575);
FORCEPROP 2 LAST SIG_NAME SPI_PCH_TPM_CS_R_N
J 0
(-4625 -3565);
DISPLAY 0.617021 (-4625 -3565);
PAINT ORANGE (-4625 -3565);
FORCEPROP 2 LASTPROP $XRERR UNIQUE?
J 0
(-4865 -3565);
DISPLAY 0.638298 (-4865 -3565);
PAINT MONO (-4865 -3565);
DISPLAY INVISIBLE (-4865 -3565);
WIRE 16 -1 (-4625 -3375)(-4050 -3375);
FORCEPROP 2 LAST SIG_NAME SPI_PCH_TPM_MOSI_R
J 0
(-4625 -3365);
DISPLAY 0.617021 (-4625 -3365);
PAINT ORANGE (-4625 -3365);
FORCEPROP 2 LASTPROP $XRERR UNIQUE?
J 0
(-4865 -3365);
DISPLAY 0.638298 (-4865 -3365);
PAINT MONO (-4865 -3365);
DISPLAY INVISIBLE (-4865 -3365);
WIRE 16 -1 (-5250 -3475)(-4825 -3475);
FORCEPROP 2 LAST SIG_NAME SPI_PCH_MISO
J 0
(-5250 -3465);
DISPLAY 0.617021 (-5250 -3465);
PAINT ORANGE (-5250 -3465);
WIRE 16 -1 (-5250 -3375)(-4825 -3375);
FORCEPROP 2 LAST SIG_NAME SPI_PCH_MOSI
J 0
(-5250 -3365);
DISPLAY 0.617021 (-5250 -3365);
PAINT ORANGE (-5250 -3365);
WIRE 16 -1 (-4650 -3175)(-4050 -3175);
FORCEPROP 2 LAST SIG_NAME SPI_PCH_TPM_CLK_R
J 0
(-4625 -3165);
DISPLAY 0.617021 (-4625 -3165);
PAINT ORANGE (-4625 -3165);
FORCEPROP 2 LASTPROP $XRERR UNIQUE?
J 0
(-4865 -3165);
DISPLAY 0.638298 (-4865 -3165);
PAINT MONO (-4865 -3165);
DISPLAY INVISIBLE (-4865 -3165);
WIRE 16 -1 (-5250 -3175)(-4850 -3175);
FORCEPROP 2 LAST SIG_NAME SPI_PCH_CLK
J 0
(-5250 -3165);
DISPLAY 0.617021 (-5250 -3165);
PAINT ORANGE (-5250 -3165);
WIRE 16 -1 (-5250 -3575)(-4850 -3575);
FORCEPROP 2 LAST SIG_NAME SPI_PCH_TPM_CS_N
J 0
(-5250 -3565);
DISPLAY 0.617021 (-5250 -3565);
PAINT ORANGE (-5250 -3565);
WIRE 16 -1 (-3350 -3425)(-2675 -3425);
FORCEPROP 2 LAST SIG_NAME IRQ_SPI_TPM_N_R
J 0
(-3135 -3425);
DISPLAY 0.617021 (-3135 -3425);
PAINT ORANGE (-3135 -3425);
FORCEPROP 2 LASTPROP $XRERR UNIQUE?
J 0
(-3375 -3425);
DISPLAY 0.638298 (-3375 -3425);
PAINT MONO (-3375 -3425);
DISPLAY INVISIBLE (-3375 -3425);
WIRE 16 -1 (-4625 -3475)(-4050 -3475);
FORCEPROP 2 LAST SIG_NAME SPI_PCH_TPM_MISO_R
J 0
(-4625 -3465);
DISPLAY 0.617021 (-4625 -3465);
PAINT ORANGE (-4625 -3465);
FORCEPROP 2 LASTPROP $XRERR UNIQUE?
J 0
(-4865 -3465);
DISPLAY 0.638298 (-4865 -3465);
PAINT MONO (-4865 -3465);
DISPLAY INVISIBLE (-4865 -3465);
DOT 1 (-3225 -3625);
DOT 1 (-3225 -3725);
FORCENOTE
BOM_COST=MIO_SECURITY
(-7550 -5675) 0;
DISPLAY LEFT (-7550 -5675);
DISPLAY 1.021277 (-7550 -5675);
PAINT PURPLE (-7550 -5675);
FORCENOTE
ROOM=TPM
(-7575 -5600) 0;
DISPLAY LEFT (-7575 -5600);
DISPLAY 1.021277 (-7575 -5600);
PAINT PURPLE (-7575 -5600);
FORCENOTE
TP FAB1 FOR BMC TPM 1120
(-2625 -3225) 0;
DISPLAY LEFT (-2625 -3225);
DISPLAY 1.021277 (-2625 -3225);
PAINT RED (-2625 -3225);
QUIT
